(kicad_pcb
	(version 20260206)
	(generator "pcbnew")
	(generator_version "10.0")
	(general
		(thickness 1.6)
		(legacy_teardrops no)
	)
	(paper "A4")
	(title_block
		(title "pdpb — Lightning_PDPB_BRD.brd")
		(comment 1 "Lightning (Wiwynn / Facebook NVMe JBOF) / footprints 593-598 of 1140")
	)
	(layers
		(0 "F.Cu" signal "TOP")
		(4 "In1.Cu" signal "L2GND")
		(6 "In2.Cu" signal "L3")
		(8 "In3.Cu" signal "L4VCC")
		(10 "In4.Cu" signal "L5VCC")
		(12 "In5.Cu" signal "L6")
		(14 "In6.Cu" signal "L7GND")
		(2 "B.Cu" signal "BOTTOM")
		(9 "F.Adhes" user "F.Adhesive")
		(11 "B.Adhes" user "B.Adhesive")
		(13 "F.Paste" user "Package Geometry/Pastemask Top")
		(15 "B.Paste" user "Package Geometry/Pastemask Bottom")
		(5 "F.SilkS" user "Ref Des/Silkscreen Top")
		(7 "B.SilkS" user "Ref Des/Silkscreen Bottom")
		(1 "F.Mask" user "Board Geometry/Soldermask Top")
		(3 "B.Mask" user "Board Geometry/Soldermask Bottom")
		(17 "Dwgs.User" user "User.Drawings")
		(19 "Cmts.User" user "User.Comments")
		(21 "Eco1.User" user "User.Eco1")
		(23 "Eco2.User" user "User.Eco2")
		(25 "Edge.Cuts" user "Board Geometry/Outline")
		(27 "Margin" user)
		(31 "F.CrtYd" user "Package Geometry/Place Bound Top")
		(29 "B.CrtYd" user "Package Geometry/Place Bound Bottom")
		(35 "F.Fab" user "Ref Des/Assembly Top")
		(33 "B.Fab" user "Ref Des/Assembly Bottom")
	)
	(footprint ""
		(layer "F.Cu")
		(at 91.313 -110.236 180)
		(property "Reference" "R9061"
			(at 0 0 180)
			(layer "F.SilkS")
			(hide yes)
			(effects
				(font
					(size 1.27 1.27)
				)
			)
		)
		(property "Value" "27R2F-GP"
			(at 0.064008 -3.993896 180)
			(unlocked yes)
			(layer "F.Fab")
			(hide yes)
			(effects
				(font
					(size 1.016 1.016)
					(thickness 0.1524)
				)
			)
		)
		(property "Device Type" "R402H16"
			(at 0.064008 -5.517896 180)
			(unlocked yes)
			(layer "F.Fab")
			(hide yes)
			(effects
				(font
					(size 1.016 1.016)
					(thickness 0.1524)
				)
			)
		)
		(duplicate_pad_numbers_are_jumpers no)
		(fp_line
			(start 0.508 -0.9398)
			(end -0.508 -0.9398)
			(stroke
				(width 0.1524)
				(type default)
			)
			(layer "F.SilkS")
		)
		(fp_line
			(start -0.508 -0.9398)
			(end -0.508 0.9398)
			(stroke
				(width 0.1524)
				(type default)
			)
			(layer "F.SilkS")
		)
		(fp_rect
			(start -0.508 0.9398)
			(end 0.508 -0.9398)
			(stroke
				(width 0)
				(type default)
			)
			(fill no)
			(layer "F.CrtYd")
		)
		(fp_rect
			(start -0.508 0.9398)
			(end 0.508 -0.9398)
			(stroke
				(width 0)
				(type default)
			)
			(fill no)
			(layer "F.Fab")
		)
		(pad "1" smd custom
			(at 0 -0.4445 180)
			(size 0.1397 0.1397)
			(layers "F.Cu" "F.Mask" "F.Paste")
			(net "PE_CLK_100M_DR13_2_R_P")
			(options
				(clearance outline)
				(anchor circle)
			)
			(primitives
				(gr_poly
					(pts
						(arc
							(start -0.1778 -0.2794)
							(mid -0.249642 -0.249642)
							(end -0.2794 -0.1778)
						)
						(arc
							(start -0.2794 0.1778)
							(mid -0.249642 0.249642)
							(end -0.1778 0.2794)
						)
						(arc
							(start 0.1778 0.2794)
							(mid 0.249642 0.249642)
							(end 0.2794 0.1778)
						)
						(arc
							(start 0.2794 -0.1778)
							(mid 0.249642 -0.249642)
							(end 0.1778 -0.2794)
						)
					)
					(width 0)
					(fill yes)
				)
			)
		)
		(pad "2" smd custom
			(at 0 0.4445 180)
			(size 0.1397 0.1397)
			(layers "F.Cu" "F.Mask" "F.Paste")
			(net "PE_CLK100M_DR13_2_P")
			(options
				(clearance outline)
				(anchor circle)
			)
			(primitives
				(gr_poly
					(pts
						(arc
							(start -0.1778 -0.2794)
							(mid -0.249642 -0.249642)
							(end -0.2794 -0.1778)
						)
						(arc
							(start -0.2794 0.1778)
							(mid -0.249642 0.249642)
							(end -0.1778 0.2794)
						)
						(arc
							(start 0.1778 0.2794)
							(mid 0.249642 0.249642)
							(end 0.2794 0.1778)
						)
						(arc
							(start 0.2794 -0.1778)
							(mid 0.249642 -0.249642)
							(end 0.1778 -0.2794)
						)
					)
					(width 0)
					(fill yes)
				)
			)
		)
	)
	(footprint ""
		(layer "F.Cu")
		(at 55.2958 -451.1548 -90)
		(property "Reference" "R9917"
			(at 0 0 270)
			(layer "F.SilkS")
			(hide yes)
			(effects
				(font
					(size 1.27 1.27)
				)
			)
		)
		(property "Value" "47KR2J-2-GP"
			(at 0.064008 -3.993896 270)
			(unlocked yes)
			(layer "F.Fab")
			(hide yes)
			(effects
				(font
					(size 1.016 1.016)
					(thickness 0.1524)
				)
			)
		)
		(property "Device Type" "R402H16"
			(at 0.064008 -5.517896 270)
			(unlocked yes)
			(layer "F.Fab")
			(hide yes)
			(effects
				(font
					(size 1.016 1.016)
					(thickness 0.1524)
				)
			)
		)
		(duplicate_pad_numbers_are_jumpers no)
		(fp_line
			(start -0.508 -0.9398)
			(end -0.508 0.9398)
			(stroke
				(width 0.1524)
				(type default)
			)
			(layer "F.SilkS")
		)
		(fp_line
			(start 0.508 -0.9398)
			(end -0.508 -0.9398)
			(stroke
				(width 0.1524)
				(type default)
			)
			(layer "F.SilkS")
		)
		(fp_rect
			(start -0.508 0.9398)
			(end 0.508 -0.9398)
			(stroke
				(width 0)
				(type default)
			)
			(fill no)
			(layer "F.CrtYd")
		)
		(fp_rect
			(start -0.508 0.9398)
			(end 0.508 -0.9398)
			(stroke
				(width 0)
				(type default)
			)
			(fill no)
			(layer "F.Fab")
		)
		(pad "1" smd custom
			(at 0 -0.4445 270)
			(size 0.1397 0.1397)
			(layers "F.Cu" "F.Mask" "F.Paste")
			(net "P3V3")
			(options
				(clearance outline)
				(anchor circle)
			)
			(primitives
				(gr_poly
					(pts
						(arc
							(start -0.1778 -0.2794)
							(mid -0.249642 -0.249642)
							(end -0.2794 -0.1778)
						)
						(arc
							(start -0.2794 0.1778)
							(mid -0.249642 0.249642)
							(end -0.1778 0.2794)
						)
						(arc
							(start 0.1778 0.2794)
							(mid 0.249642 0.249642)
							(end 0.2794 0.1778)
						)
						(arc
							(start 0.2794 -0.1778)
							(mid 0.249642 -0.249642)
							(end 0.1778 -0.2794)
						)
					)
					(width 0)
					(fill yes)
				)
			)
		)
		(pad "2" smd custom
			(at 0 0.4445 270)
			(size 0.1397 0.1397)
			(layers "F.Cu" "F.Mask" "F.Paste")
			(net "ATTN_LED_DR5_N")
			(options
				(clearance outline)
				(anchor circle)
			)
			(primitives
				(gr_poly
					(pts
						(arc
							(start -0.1778 -0.2794)
							(mid -0.249642 -0.249642)
							(end -0.2794 -0.1778)
						)
						(arc
							(start -0.2794 0.1778)
							(mid -0.249642 0.249642)
							(end -0.1778 0.2794)
						)
						(arc
							(start 0.1778 0.2794)
							(mid 0.249642 0.249642)
							(end 0.2794 0.1778)
						)
						(arc
							(start 0.2794 -0.1778)
							(mid 0.249642 -0.249642)
							(end 0.1778 -0.2794)
						)
					)
					(width 0)
					(fill yes)
				)
			)
		)
	)
	(footprint ""
		(layer "F.Cu")
		(at 56.134 -447.04 180)
		(property "Reference" "Q54"
			(at 0 0 180)
			(layer "F.SilkS")
			(hide yes)
			(effects
				(font
					(size 1.27 1.27)
				)
			)
		)
		(property "Value" "2N7002A-7-GP"
			(at 0.127 -8.9662 180)
			(unlocked yes)
			(layer "F.Fab")
			(hide yes)
			(effects
				(font
					(size 1.016 1.016)
					(thickness 0.1524)
				)
			)
		)
		(property "Device Type" "SOT23DGS2D4H48"
			(at 0.127 -10.4902 180)
			(unlocked yes)
			(layer "F.Fab")
			(hide yes)
			(effects
				(font
					(size 1.016 1.016)
					(thickness 0.1524)
				)
			)
		)
		(duplicate_pad_numbers_are_jumpers no)
		(fp_line
			(start 1.651 1.778)
			(end 1.651 -1.778)
			(stroke
				(width 0.1524)
				(type default)
			)
			(layer "F.SilkS")
		)
		(fp_line
			(start 1.651 -1.778)
			(end -1.651 -1.778)
			(stroke
				(width 0.1524)
				(type default)
			)
			(layer "F.SilkS")
		)
		(fp_line
			(start -1.651 1.778)
			(end 1.651 1.778)
			(stroke
				(width 0.1524)
				(type default)
			)
			(layer "F.SilkS")
		)
		(fp_line
			(start -1.651 -1.778)
			(end -1.651 1.778)
			(stroke
				(width 0.1524)
				(type default)
			)
			(layer "F.SilkS")
		)
		(fp_poly
			(pts
				(xy -1.778 1.8796) (xy -1.778 -1.8796) (xy 1.778 -1.8796) (xy 1.778 1.8796)
			)
			(stroke
				(width 0)
				(type default)
			)
			(fill no)
			(layer "F.CrtYd")
		)
		(fp_poly
			(pts
				(xy -1.778 1.8796) (xy -1.778 -1.8796) (xy 1.778 -1.8796) (xy 1.778 1.8796)
			)
			(stroke
				(width 0)
				(type default)
			)
			(fill no)
			(layer "F.Fab")
		)
		(pad "D" smd custom
			(at 0 -0.9525 180)
			(size 0.1905 0.1905)
			(layers "F.Cu" "F.Mask" "F.Paste")
			(net "SSD5_CLK0_OE_MOS_N")
			(options
				(clearance outline)
				(anchor circle)
			)
			(primitives
				(gr_poly
					(pts
						(arc
							(start -0.1778 0.5715)
							(mid -0.321484 0.511984)
							(end -0.381 0.3683)
						)
						(arc
							(start -0.381 -0.3683)
							(mid -0.321484 -0.511984)
							(end -0.1778 -0.5715)
						)
						(arc
							(start 0.1778 -0.5715)
							(mid 0.321484 -0.511984)
							(end 0.381 -0.3683)
						)
						(arc
							(start 0.381 0.3683)
							(mid 0.321484 0.511984)
							(end 0.1778 0.5715)
						)
					)
					(width 0)
					(fill yes)
				)
			)
		)
		(pad "G" smd custom
			(at -0.98425 0.9525 180)
			(size 0.1905 0.1905)
			(layers "F.Cu" "F.Mask" "F.Paste")
			(net "SSD5_CLK0_OE_R_N")
			(options
				(clearance outline)
				(anchor circle)
			)
			(primitives
				(gr_poly
					(pts
						(arc
							(start -0.1778 0.5715)
							(mid -0.321484 0.511984)
							(end -0.381 0.3683)
						)
						(arc
							(start -0.381 -0.3683)
							(mid -0.321484 -0.511984)
							(end -0.1778 -0.5715)
						)
						(arc
							(start 0.1778 -0.5715)
							(mid 0.321484 -0.511984)
							(end 0.381 -0.3683)
						)
						(arc
							(start 0.381 0.3683)
							(mid 0.321484 0.511984)
							(end 0.1778 0.5715)
						)
					)
					(width 0)
					(fill yes)
				)
			)
		)
		(pad "S" smd custom
			(at 0.98425 0.9525 180)
			(size 0.1905 0.1905)
			(layers "F.Cu" "F.Mask" "F.Paste")
			(net "GND")
			(options
				(clearance outline)
				(anchor circle)
			)
			(primitives
				(gr_poly
					(pts
						(arc
							(start -0.1778 0.5715)
							(mid -0.321484 0.511984)
							(end -0.381 0.3683)
						)
						(arc
							(start -0.381 -0.3683)
							(mid -0.321484 -0.511984)
							(end -0.1778 -0.5715)
						)
						(arc
							(start 0.1778 -0.5715)
							(mid 0.321484 -0.511984)
							(end 0.381 -0.3683)
						)
						(arc
							(start 0.381 0.3683)
							(mid 0.321484 0.511984)
							(end 0.1778 0.5715)
						)
					)
					(width 0)
					(fill yes)
				)
			)
		)
	)
	(footprint ""
		(layer "F.Cu")
		(at 85.471 -430.53 -90)
		(property "Reference" "R9034"
			(at 0 0 270)
			(layer "F.SilkS")
			(hide yes)
			(effects
				(font
					(size 1.27 1.27)
				)
			)
		)
		(property "Value" "4K7R2F-GP"
			(at 0.064008 -3.993896 270)
			(unlocked yes)
			(layer "F.Fab")
			(hide yes)
			(effects
				(font
					(size 1.016 1.016)
					(thickness 0.1524)
				)
			)
		)
		(property "Device Type" "R402H16"
			(at 0.064008 -5.517896 270)
			(unlocked yes)
			(layer "F.Fab")
			(hide yes)
			(effects
				(font
					(size 1.016 1.016)
					(thickness 0.1524)
				)
			)
		)
		(duplicate_pad_numbers_are_jumpers no)
		(fp_line
			(start -0.508 -0.9398)
			(end -0.508 0.9398)
			(stroke
				(width 0.1524)
				(type default)
			)
			(layer "F.SilkS")
		)
		(fp_line
			(start 0.508 -0.9398)
			(end -0.508 -0.9398)
			(stroke
				(width 0.1524)
				(type default)
			)
			(layer "F.SilkS")
		)
		(fp_rect
			(start -0.508 0.9398)
			(end 0.508 -0.9398)
			(stroke
				(width 0)
				(type default)
			)
			(fill no)
			(layer "F.CrtYd")
		)
		(fp_rect
			(start -0.508 0.9398)
			(end 0.508 -0.9398)
			(stroke
				(width 0)
				(type default)
			)
			(fill no)
			(layer "F.Fab")
		)
		(pad "1" smd custom
			(at 0 -0.4445 270)
			(size 0.1397 0.1397)
			(layers "F.Cu" "F.Mask" "F.Paste")
			(net "CLK_BUF_EU1_SMB_A0_TRI")
			(options
				(clearance outline)
				(anchor circle)
			)
			(primitives
				(gr_poly
					(pts
						(arc
							(start -0.1778 -0.2794)
							(mid -0.249642 -0.249642)
							(end -0.2794 -0.1778)
						)
						(arc
							(start -0.2794 0.1778)
							(mid -0.249642 0.249642)
							(end -0.1778 0.2794)
						)
						(arc
							(start 0.1778 0.2794)
							(mid 0.249642 0.249642)
							(end 0.2794 0.1778)
						)
						(arc
							(start 0.2794 -0.1778)
							(mid 0.249642 -0.249642)
							(end 0.1778 -0.2794)
						)
					)
					(width 0)
					(fill yes)
				)
			)
		)
		(pad "2" smd custom
			(at 0 0.4445 270)
			(size 0.1397 0.1397)
			(layers "F.Cu" "F.Mask" "F.Paste")
			(net "GND")
			(options
				(clearance outline)
				(anchor circle)
			)
			(primitives
				(gr_poly
					(pts
						(arc
							(start -0.1778 -0.2794)
							(mid -0.249642 -0.249642)
							(end -0.2794 -0.1778)
						)
						(arc
							(start -0.2794 0.1778)
							(mid -0.249642 0.249642)
							(end -0.1778 0.2794)
						)
						(arc
							(start 0.1778 0.2794)
							(mid 0.249642 0.249642)
							(end 0.2794 0.1778)
						)
						(arc
							(start 0.2794 -0.1778)
							(mid 0.249642 -0.249642)
							(end 0.1778 -0.2794)
						)
					)
					(width 0)
					(fill yes)
				)
			)
		)
	)
	(footprint ""
		(layer "F.Cu")
		(at 32.2326 -108.1024 90)
		(property "Reference" "U22"
			(at 0 0 90)
			(layer "F.SilkS")
			(hide yes)
			(effects
				(font
					(size 1.27 1.27)
				)
			)
		)
		(property "Value" "P2003EVG-GP"
			(at 0 -11.1252 90)
			(unlocked yes)
			(layer "F.Fab")
			(hide yes)
			(effects
				(font
					(size 1.016 1.016)
					(thickness 0.1524)
				)
			)
		)
		(property "Device Type" "SOIC8H79"
			(at 0 -12.6492 90)
			(unlocked yes)
			(layer "F.Fab")
			(hide yes)
			(effects
				(font
					(size 1.016 1.016)
					(thickness 0.1524)
				)
			)
		)
		(duplicate_pad_numbers_are_jumpers no)
		(fp_line
			(start 2.1336 -1.4224)
			(end -2.7432 -1.4224)
			(stroke
				(width 0.1524)
				(type default)
			)
			(layer "F.SilkS")
		)
		(fp_line
			(start -2.7432 -1.4224)
			(end -2.7432 1.4224)
			(stroke
				(width 0.1524)
				(type default)
			)
			(layer "F.SilkS")
		)
		(fp_line
			(start -2.7432 -0.508)
			(end -2.2352 0)
			(stroke
				(width 0.1524)
				(type default)
			)
			(layer "F.SilkS")
		)
		(fp_line
			(start -2.2352 0)
			(end -2.7432 0.508)
			(stroke
				(width 0.1524)
				(type default)
			)
			(layer "F.SilkS")
		)
		(fp_line
			(start 2.1336 1.4224)
			(end 2.1336 -1.4224)
			(stroke
				(width 0.1524)
				(type default)
			)
			(layer "F.SilkS")
		)
		(fp_line
			(start -2.7432 1.4224)
			(end 2.1336 1.4224)
			(stroke
				(width 0.1524)
				(type default)
			)
			(layer "F.SilkS")
		)
		(fp_line
			(start -2.6162 3.429)
			(end -2.6162 1.4732)
			(stroke
				(width 0.4064)
				(type default)
			)
			(layer "F.SilkS")
		)
		(fp_poly
			(pts
				(xy 2.2098 -1.4224) (xy 2.2098 1.4224) (xy -2.2225 1.4224) (xy -2.2225 -1.4224)
			)
			(stroke
				(width 0)
				(type default)
			)
			(fill yes)
			(layer "F.SilkS")
		)
		(fp_rect
			(start -2.4511 2.9972)
			(end 2.4511 -2.9972)
			(stroke
				(width 0)
				(type default)
			)
			(fill no)
			(layer "F.CrtYd")
		)
		(fp_poly
			(pts
				(xy -2.8194 3.6322) (xy -2.8194 -3.6322) (xy 2.8194 -3.6322) (xy 2.8194 -2.2987) (xy 2.4511 -2.2987)
				(xy 2.4511 -2.9972) (xy -2.4511 -2.9972) (xy -2.4511 2.9972) (xy 2.4511 2.9972) (xy 2.4511 -2.286)
				(xy 2.8194 -2.286) (xy 2.8194 3.6322)
			)
			(stroke
				(width 0)
				(type default)
			)
			(fill no)
			(layer "F.CrtYd")
		)
		(fp_rect
			(start -2.8194 3.6322)
			(end 2.8194 -3.6322)
			(stroke
				(width 0)
				(type default)
			)
			(fill no)
			(layer "F.Fab")
		)
		(pad "1" smd rect
			(at -1.905 2.54 90)
			(size 0.635 1.651)
			(layers "F.Cu" "F.Mask" "F.Paste")
			(net "P12V")
		)
		(pad "2" smd rect
			(at -0.635 2.54 90)
			(size 0.635 1.651)
			(layers "F.Cu" "F.Mask" "F.Paste")
			(net "P12V")
		)
		(pad "3" smd rect
			(at 0.635 2.54 90)
			(size 0.635 1.651)
			(layers "F.Cu" "F.Mask" "F.Paste")
			(net "P12V")
		)
		(pad "4" smd rect
			(at 1.905 2.54 90)
			(size 0.635 1.651)
			(layers "F.Cu" "F.Mask" "F.Paste")
			(net "SW_SSD13_N")
		)
		(pad "5" smd rect
			(at 1.905 -2.54 90)
			(size 0.635 1.651)
			(layers "F.Cu" "F.Mask" "F.Paste")
			(net "P12V_SSD13")
		)
		(pad "6" smd rect
			(at 0.635 -2.54 90)
			(size 0.635 1.651)
			(layers "F.Cu" "F.Mask" "F.Paste")
			(net "P12V_SSD13")
		)
		(pad "7" smd rect
			(at -0.635 -2.54 90)
			(size 0.635 1.651)
			(layers "F.Cu" "F.Mask" "F.Paste")
			(net "P12V_SSD13")
		)
		(pad "8" smd rect
			(at -1.905 -2.54 90)
			(size 0.635 1.651)
			(layers "F.Cu" "F.Mask" "F.Paste")
			(net "P12V_SSD13")
		)
	)
	(footprint ""
		(layer "F.Cu")
		(at 82.931 -211.9376 90)
		(property "Reference" "R9355"
			(at 0 0 90)
			(layer "F.SilkS")
			(hide yes)
			(effects
				(font
					(size 1.27 1.27)
				)
			)
		)
		(property "Value" "2D2R2F-GP"
			(at 0.064008 -3.993896 90)
			(unlocked yes)
			(layer "F.Fab")
			(hide yes)
			(effects
				(font
					(size 1.016 1.016)
					(thickness 0.1524)
				)
			)
		)
		(property "Device Type" "R402H16"
			(at 0.064008 -5.517896 90)
			(unlocked yes)
			(layer "F.Fab")
			(hide yes)
			(effects
				(font
					(size 1.016 1.016)
					(thickness 0.1524)
				)
			)
		)
		(duplicate_pad_numbers_are_jumpers no)
		(fp_line
			(start 0.508 -0.9398)
			(end -0.508 -0.9398)
			(stroke
				(width 0.1524)
				(type default)
			)
			(layer "F.SilkS")
		)
		(fp_line
			(start -0.508 -0.9398)
			(end -0.508 0.9398)
			(stroke
				(width 0.1524)
				(type default)
			)
			(layer "F.SilkS")
		)
		(fp_rect
			(start -0.508 0.9398)
			(end 0.508 -0.9398)
			(stroke
				(width 0)
				(type default)
			)
			(fill no)
			(layer "F.CrtYd")
		)
		(fp_rect
			(start -0.508 0.9398)
			(end 0.508 -0.9398)
			(stroke
				(width 0)
				(type default)
			)
			(fill no)
			(layer "F.Fab")
		)
		(pad "1" smd custom
			(at 0 -0.4445 90)
			(size 0.1397 0.1397)
			(layers "F.Cu" "F.Mask" "F.Paste")
			(net "VDD_DIFF_3")
			(options
				(clearance outline)
				(anchor circle)
			)
			(primitives
				(gr_poly
					(pts
						(arc
							(start -0.1778 -0.2794)
							(mid -0.249642 -0.249642)
							(end -0.2794 -0.1778)
						)
						(arc
							(start -0.2794 0.1778)
							(mid -0.249642 0.249642)
							(end -0.1778 0.2794)
						)
						(arc
							(start 0.1778 0.2794)
							(mid 0.249642 0.249642)
							(end 0.2794 0.1778)
						)
						(arc
							(start 0.2794 -0.1778)
							(mid 0.249642 -0.249642)
							(end 0.1778 -0.2794)
						)
					)
					(width 0)
					(fill yes)
				)
			)
		)
		(pad "2" smd custom
			(at 0 0.4445 90)
			(size 0.1397 0.1397)
			(layers "F.Cu" "F.Mask" "F.Paste")
			(net "VDDR_3")
			(options
				(clearance outline)
				(anchor circle)
			)
			(primitives
				(gr_poly
					(pts
						(arc
							(start -0.1778 -0.2794)
							(mid -0.249642 -0.249642)
							(end -0.2794 -0.1778)
						)
						(arc
							(start -0.2794 0.1778)
							(mid -0.249642 0.249642)
							(end -0.1778 0.2794)
						)
						(arc
							(start 0.1778 0.2794)
							(mid 0.249642 0.249642)
							(end 0.2794 0.1778)
						)
						(arc
							(start 0.2794 -0.1778)
							(mid 0.249642 -0.249642)
							(end 0.1778 -0.2794)
						)
					)
					(width 0)
					(fill yes)
				)
			)
		)
	)
)
